# S9S_MB_2U (Grand Teton) — schematic netlist excerpt (pin names and nets, part order shuffled) for the footprints in the layout excerpt that follows; sources: Cadence DE-HDL packaged netlist, KiCad conversion of 03242023_DA0F0TMBIJ0_F0T_Motherboard_J_brd_V01_OCP.brd

PC248  Q_CAP  2.2UF 10V 10% X6S  pkg C0402  page 269 : A = PVCCIN_CPU0_VDD6 ; B = GND
C401  Q_CAP  22UF 4V 20% X6S  pkg C0402  page 74 : A = PVCCD_HV_CPU0 ; B = GND

(kicad_pcb
	(version 20260206)
	(generator "pcbnew")
	(generator_version "10.0")
	(general
		(thickness 1.6)
		(legacy_teardrops no)
	)
	(paper "A4")
	(title_block
		(title "03242023_DA0F0TMBIJ0_F0T_Motherboard_J_brd_V01_OCP.brd")
		(comment 1 "Grand Teton / footprints 1218-1219 of 6105")
	)
	(layers
		(0 "F.Cu" signal "TOP")
		(4 "In1.Cu" signal "GND")
		(6 "In2.Cu" signal "IN1")
		(8 "In3.Cu" signal "GND1")
		(10 "In4.Cu" signal "IN2")
		(12 "In5.Cu" signal "GND2")
		(14 "In6.Cu" signal "IN3")
		(16 "In7.Cu" signal "GND3")
		(18 "In8.Cu" signal "VCC")
		(20 "In9.Cu" signal "VCC1")
		(22 "In10.Cu" signal "GND4")
		(24 "In11.Cu" signal "IN4")
		(26 "In12.Cu" signal "GND5")
		(28 "In13.Cu" signal "IN5")
		(30 "In14.Cu" signal "GND6")
		(32 "In15.Cu" signal "IN6")
		(34 "In16.Cu" signal "GND7")
		(2 "B.Cu" signal "BOTTOM")
		(9 "F.Adhes" user "F.Adhesive")
		(11 "B.Adhes" user "B.Adhesive")
		(13 "F.Paste" user "Package Geometry/Pastemask Top")
		(15 "B.Paste" user "Package Geometry/Pastemask Bottom")
		(5 "F.SilkS" user "Ref Des/Silkscreen Top")
		(7 "B.SilkS" user "Ref Des/Silkscreen Bottom")
		(1 "F.Mask" user "Board Geometry/Soldermask Top")
		(3 "B.Mask" user "Board Geometry/Soldermask Bottom")
		(17 "Dwgs.User" user "User.Drawings")
		(19 "Cmts.User" user "User.Comments")
		(21 "Eco1.User" user "User.Eco1")
		(23 "Eco2.User" user "User.Eco2")
		(25 "Edge.Cuts" user "Board Geometry/Outline")
		(27 "Margin" user)
		(31 "F.CrtYd" user "Package Geometry/Place Bound Top")
		(29 "B.CrtYd" user "Package Geometry/Place Bound Bottom")
		(35 "F.Fab" user "Ref Des/Assembly Top")
		(33 "B.Fab" user "Ref Des/Assembly Bottom")
	)
	(footprint ""
		(layer "F.Cu")
		(at 352.289618 -245.634002 -90)
		(property "Reference" "C401"
			(at 0 0 270)
			(layer "F.SilkS")
			(hide yes)
			(effects
				(font
					(size 1.27 1.27)
				)
			)
		)
		(property "Value" ""
			(at 0 0 270)
			(layer "F.Fab")
			(effects
				(font
					(size 1.27 1.27)
				)
			)
		)
		(duplicate_pad_numbers_are_jumpers no)
		(fp_line
			(start -0.7874 0.4064)
			(end -0.7874 -0.4064)
			(stroke
				(width 0.1524)
				(type default)
			)
			(layer "F.SilkS")
		)
		(fp_line
			(start 0.7874 0.4064)
			(end -0.7874 0.4064)
			(stroke
				(width 0.1524)
				(type default)
			)
			(layer "F.SilkS")
		)
		(fp_line
			(start -0.7874 -0.4064)
			(end 0.7874 -0.4064)
			(stroke
				(width 0.1524)
				(type default)
			)
			(layer "F.SilkS")
		)
		(fp_line
			(start 0.7874 -0.4064)
			(end 0.7874 0.4064)
			(stroke
				(width 0.1524)
				(type default)
			)
			(layer "F.SilkS")
		)
		(fp_line
			(start -0.67945 0.3048)
			(end -0.67945 -0.305054)
			(stroke
				(width 0.1)
				(type default)
			)
			(layer "F.Fab")
		)
		(fp_line
			(start -0.12065 0.3048)
			(end -0.67945 0.3048)
			(stroke
				(width 0.1)
				(type default)
			)
			(layer "F.Fab")
		)
		(fp_line
			(start 0.120396 0.3048)
			(end 0.120396 0.2794)
			(stroke
				(width 0.1)
				(type default)
			)
			(layer "F.Fab")
		)
		(fp_line
			(start 0.67945 0.3048)
			(end 0.120396 0.3048)
			(stroke
				(width 0.1)
				(type default)
			)
			(layer "F.Fab")
		)
		(fp_line
			(start -0.12065 0.2794)
			(end -0.12065 0.3048)
			(stroke
				(width 0.1)
				(type default)
			)
			(layer "F.Fab")
		)
		(fp_line
			(start 0.120396 0.2794)
			(end -0.12065 0.2794)
			(stroke
				(width 0.1)
				(type default)
			)
			(layer "F.Fab")
		)
		(fp_line
			(start -0.12065 -0.2794)
			(end 0.12065 -0.2794)
			(stroke
				(width 0.1)
				(type default)
			)
			(layer "F.Fab")
		)
		(fp_line
			(start 0.12065 -0.2794)
			(end 0.12065 -0.3048)
			(stroke
				(width 0.1)
				(type default)
			)
			(layer "F.Fab")
		)
		(fp_line
			(start 0.12065 -0.3048)
			(end 0.67945 -0.3048)
			(stroke
				(width 0.1)
				(type default)
			)
			(layer "F.Fab")
		)
		(fp_line
			(start 0.67945 -0.3048)
			(end 0.67945 0.3048)
			(stroke
				(width 0.1)
				(type default)
			)
			(layer "F.Fab")
		)
		(fp_line
			(start -0.67945 -0.305054)
			(end -0.12065 -0.305054)
			(stroke
				(width 0.1)
				(type default)
			)
			(layer "F.Fab")
		)
		(fp_line
			(start -0.12065 -0.305054)
			(end -0.12065 -0.2794)
			(stroke
				(width 0.1)
				(type default)
			)
			(layer "F.Fab")
		)
		(pad "1" smd circle
			(at -0.40005 0 270)
			(size 0 0)
			(layers "F.Cu" "F.Mask" "F.Paste")
			(net "PVCCD_HV_CPU0")
		)
		(pad "2" smd circle
			(at 0.40005 0 270)
			(size 0 0)
			(layers "F.Cu" "F.Mask" "F.Paste")
			(net "GND")
		)
	)
	(footprint ""
		(layer "F.Cu")
		(at 333.20228 -339.602572 90)
		(property "Reference" "PC248"
			(at 0 0 90)
			(layer "F.SilkS")
			(hide yes)
			(effects
				(font
					(size 1.27 1.27)
				)
			)
		)
		(property "Value" ""
			(at 0 0 90)
			(layer "F.Fab")
			(effects
				(font
					(size 1.27 1.27)
				)
			)
		)
		(duplicate_pad_numbers_are_jumpers no)
		(fp_line
			(start 0.7874 -0.4064)
			(end 0.7874 0.4064)
			(stroke
				(width 0.1524)
				(type default)
			)
			(layer "F.SilkS")
		)
		(fp_line
			(start -0.7874 -0.4064)
			(end 0.7874 -0.4064)
			(stroke
				(width 0.1524)
				(type default)
			)
			(layer "F.SilkS")
		)
		(fp_line
			(start 0.7874 0.4064)
			(end -0.7874 0.4064)
			(stroke
				(width 0.1524)
				(type default)
			)
			(layer "F.SilkS")
		)
		(fp_line
			(start -0.7874 0.4064)
			(end -0.7874 -0.4064)
			(stroke
				(width 0.1524)
				(type default)
			)
			(layer "F.SilkS")
		)
		(fp_line
			(start -0.12065 -0.305054)
			(end -0.12065 -0.2794)
			(stroke
				(width 0.1)
				(type default)
			)
			(layer "F.Fab")
		)
		(fp_line
			(start -0.67945 -0.305054)
			(end -0.12065 -0.305054)
			(stroke
				(width 0.1)
				(type default)
			)
			(layer "F.Fab")
		)
		(fp_line
			(start 0.67945 -0.3048)
			(end 0.67945 0.3048)
			(stroke
				(width 0.1)
				(type default)
			)
			(layer "F.Fab")
		)
		(fp_line
			(start 0.12065 -0.3048)
			(end 0.67945 -0.3048)
			(stroke
				(width 0.1)
				(type default)
			)
			(layer "F.Fab")
		)
		(fp_line
			(start 0.12065 -0.2794)
			(end 0.12065 -0.3048)
			(stroke
				(width 0.1)
				(type default)
			)
			(layer "F.Fab")
		)
		(fp_line
			(start -0.12065 -0.2794)
			(end 0.12065 -0.2794)
			(stroke
				(width 0.1)
				(type default)
			)
			(layer "F.Fab")
		)
		(fp_line
			(start 0.120396 0.2794)
			(end -0.12065 0.2794)
			(stroke
				(width 0.1)
				(type default)
			)
			(layer "F.Fab")
		)
		(fp_line
			(start -0.12065 0.2794)
			(end -0.12065 0.3048)
			(stroke
				(width 0.1)
				(type default)
			)
			(layer "F.Fab")
		)
		(fp_line
			(start 0.67945 0.3048)
			(end 0.120396 0.3048)
			(stroke
				(width 0.1)
				(type default)
			)
			(layer "F.Fab")
		)
		(fp_line
			(start 0.120396 0.3048)
			(end 0.120396 0.2794)
			(stroke
				(width 0.1)
				(type default)
			)
			(layer "F.Fab")
		)
		(fp_line
			(start -0.12065 0.3048)
			(end -0.67945 0.3048)
			(stroke
				(width 0.1)
				(type default)
			)
			(layer "F.Fab")
		)
		(fp_line
			(start -0.67945 0.3048)
			(end -0.67945 -0.305054)
			(stroke
				(width 0.1)
				(type default)
			)
			(layer "F.Fab")
		)
		(pad "1" smd circle
			(at -0.40005 0 90)
			(size 0 0)
			(layers "F.Cu" "F.Mask" "F.Paste")
			(net "PVCCIN_CPU0_VDD6")
		)
		(pad "2" smd circle
			(at 0.40005 0 90)
			(size 0 0)
			(layers "F.Cu" "F.Mask" "F.Paste")
			(net "GND")
		)
	)
)
